FILE_TYPE = MACRO_DRAWING;
SET COLOR_WIRE YELLOW;
SET COLOR_PROP ORANGE;
SET COLOR_DOT WHITE;
SET COLOR_ARC YELLOW;
SET COLOR_BODY GREEN;
SET COLOR_NOTE PURPLE;
SET PROP_DISPLAY VALUE;
SET PAGE_NUMBER P66;
FORCEADD QUANTA_TITLE_BLOCK_C..1
(0 0);
FORCEPROP 1 LAST CUSTOM_TXT_CDS <NAME_2>
J 0
(-3175 50);
FORCEPROP 1 LAST CUSTOM_TXT_CDS <NAME_1>
J 0
(-3175 175);
FORCEPROP 1 LAST CUSTOM_TXT_CDS <Q_NUMBER>
J 0
(-1403 103);
DISPLAY 1.212766 (-1403 103);
FORCEPROP 1 LAST CUSTOM_TXT_CDS <Q_PROJ>
J 0
(-2382 102);
DISPLAY 1.212766 (-2382 102);
FORCEPROP 1 LAST CUSTOM_TXT_CDS <Q_REV>
J 0
(-184 103);
DISPLAY 1.212766 (-184 103);
FORCEPROP 1 LAST CUSTOM_TXT_CDS <CON_LAST_MODIFIED>
J 0
(-1885 15);
DISPLAY 0.978723 (-1885 15);
FORCEPROP 1 LAST CUSTOM_TXT_CDS <CON_PAGE_NUM> OF <CON_TOTAL_PAGES>
J 0
(-446 18);
DISPLAY 0.978723 (-446 18);
FORCEPROP 1 LAST Q_TITLE AC CAPS CPU1 P2/P3 TX
J 0
(-9275 75);
DISPLAY 2.446809 (-9275 75);
PAINT GREEN (-9275 75);
FORCEPROP 1 LAST Q_DEPT BU9
J 1
(-3763 49);
DISPLAY 1.957447 (-3763 49);
PAINT GREEN (-3763 49);
FORCEPROP 2 LAST CDS_LIB pure_quanta
J 0
(0 0);
DISPLAY INVISIBLE (0 0);
FORCEPROP 1 LAST CDS_LMAN_SYM_OUTLINE -9475,6775,100,-125
J 0
(0 0);
DISPLAY 0.468085 (0 0);
PAINT GREEN (0 0);
DISPLAY INVISIBLE (0 0);
FORCEPROP 2 LAST PAGE_BORDER TRUE
J 0
(-7890 5250);
DISPLAY 0.638298 (-7890 5250);
PAINT PINK (-7890 5250);
DISPLAY INVISIBLE (-7890 5250);
FORCEPROP 1 LAST COMMENT_BODY TRUE
J 0
(12 -13);
DISPLAY 0.978723 (12 -13);
PAINT GREEN (12 -13);
DISPLAY INVISIBLE (12 -13);
FORCEPROP 2 LAST CDS_XR_PAGE_TITLE CR-66 : @T6G_MB_LIB.T6G(SCH_1):PAGE66
J 0
(-7890 5250);
DISPLAY 0.638298 (-7890 5250);
PAINT PINK (-7890 5250);
DISPLAY INVISIBLE (-7890 5250);
FORCEPROP 2 LAST CUSTOM_TXT_CDS <XR_PAGE_TITLE>
J 0
(-7890 5250);
DISPLAY 0.638298 (-7890 5250);
PAINT PINK (-7890 5250);
DISPLAY INVISIBLE (-7890 5250);
FORCEPROP 0 LAST CDS_CON_LAST_MODIFIED Thu Mar 10 20:15:20 2022
J 0
(-1885 15);
DISPLAY INVISIBLE (-1885 15);
QUIT
